# S9S_MB_2U (Grand Teton) — schematic netlist excerpt (pin names and nets, part order shuffled) for the footprints in the layout excerpt that follows; sources: Cadence DE-HDL packaged netlist, KiCad conversion of 03242023_DA0F0TMBIJ0_F0T_Motherboard_J_brd_V01_OCP.brd

R3049  Q_RES  0 5% CHIP  pkg 0402LF  page 215 : A = IRQ_SML1_PMBUS_ALERT_N ; B = IRQ_PSU_ALERT_R_N
C988  Q_CAP  10UF 6.3V 20% X6S  pkg C0402  page 74 : A = PVCCIN_CPU0 ; B = GND

(kicad_pcb
	(version 20260206)
	(generator "pcbnew")
	(generator_version "10.0")
	(general
		(thickness 1.6)
		(legacy_teardrops no)
	)
	(paper "A4")
	(title_block
		(title "03242023_DA0F0TMBIJ0_F0T_Motherboard_J_brd_V01_OCP.brd")
		(comment 1 "Grand Teton / footprints 959-960 of 6105")
	)
	(layers
		(0 "F.Cu" signal "TOP")
		(4 "In1.Cu" signal "GND")
		(6 "In2.Cu" signal "IN1")
		(8 "In3.Cu" signal "GND1")
		(10 "In4.Cu" signal "IN2")
		(12 "In5.Cu" signal "GND2")
		(14 "In6.Cu" signal "IN3")
		(16 "In7.Cu" signal "GND3")
		(18 "In8.Cu" signal "VCC")
		(20 "In9.Cu" signal "VCC1")
		(22 "In10.Cu" signal "GND4")
		(24 "In11.Cu" signal "IN4")
		(26 "In12.Cu" signal "GND5")
		(28 "In13.Cu" signal "IN5")
		(30 "In14.Cu" signal "GND6")
		(32 "In15.Cu" signal "IN6")
		(34 "In16.Cu" signal "GND7")
		(2 "B.Cu" signal "BOTTOM")
		(9 "F.Adhes" user "F.Adhesive")
		(11 "B.Adhes" user "B.Adhesive")
		(13 "F.Paste" user "Package Geometry/Pastemask Top")
		(15 "B.Paste" user "Package Geometry/Pastemask Bottom")
		(5 "F.SilkS" user "Ref Des/Silkscreen Top")
		(7 "B.SilkS" user "Ref Des/Silkscreen Bottom")
		(1 "F.Mask" user "Board Geometry/Soldermask Top")
		(3 "B.Mask" user "Board Geometry/Soldermask Bottom")
		(17 "Dwgs.User" user "User.Drawings")
		(19 "Cmts.User" user "User.Comments")
		(21 "Eco1.User" user "User.Eco1")
		(23 "Eco2.User" user "User.Eco2")
		(25 "Edge.Cuts" user "Board Geometry/Outline")
		(27 "Margin" user)
		(31 "F.CrtYd" user "Package Geometry/Place Bound Top")
		(29 "B.CrtYd" user "Package Geometry/Place Bound Bottom")
		(35 "F.Fab" user "Ref Des/Assembly Top")
		(33 "B.Fab" user "Ref Des/Assembly Bottom")
	)
	(footprint ""
		(layer "F.Cu")
		(at 193.38036 -116.804948 180)
		(property "Reference" "R3049"
			(at 0 0 180)
			(layer "F.SilkS")
			(hide yes)
			(effects
				(font
					(size 1.27 1.27)
				)
			)
		)
		(property "Value" ""
			(at 0 0 180)
			(layer "F.Fab")
			(effects
				(font
					(size 1.27 1.27)
				)
			)
		)
		(duplicate_pad_numbers_are_jumpers no)
		(fp_line
			(start 0.7874 0.4064)
			(end -0.7874 0.4064)
			(stroke
				(width 0.1524)
				(type default)
			)
			(layer "F.SilkS")
		)
		(fp_line
			(start 0.7874 -0.4064)
			(end 0.7874 0.4064)
			(stroke
				(width 0.1524)
				(type default)
			)
			(layer "F.SilkS")
		)
		(fp_line
			(start -0.7874 0.4064)
			(end -0.7874 -0.4064)
			(stroke
				(width 0.1524)
				(type default)
			)
			(layer "F.SilkS")
		)
		(fp_line
			(start -0.7874 -0.4064)
			(end 0.7874 -0.4064)
			(stroke
				(width 0.1524)
				(type default)
			)
			(layer "F.SilkS")
		)
		(fp_line
			(start 0.67945 0.3048)
			(end 0.120396 0.3048)
			(stroke
				(width 0.1)
				(type default)
			)
			(layer "F.Fab")
		)
		(fp_line
			(start 0.67945 -0.3048)
			(end 0.67945 0.3048)
			(stroke
				(width 0.1)
				(type default)
			)
			(layer "F.Fab")
		)
		(fp_line
			(start 0.12065 -0.2794)
			(end 0.12065 -0.3048)
			(stroke
				(width 0.1)
				(type default)
			)
			(layer "F.Fab")
		)
		(fp_line
			(start 0.12065 -0.3048)
			(end 0.67945 -0.3048)
			(stroke
				(width 0.1)
				(type default)
			)
			(layer "F.Fab")
		)
		(fp_line
			(start 0.120396 0.3048)
			(end 0.120396 0.2794)
			(stroke
				(width 0.1)
				(type default)
			)
			(layer "F.Fab")
		)
		(fp_line
			(start 0.120396 0.2794)
			(end -0.12065 0.2794)
			(stroke
				(width 0.1)
				(type default)
			)
			(layer "F.Fab")
		)
		(fp_line
			(start -0.12065 0.3048)
			(end -0.67945 0.3048)
			(stroke
				(width 0.1)
				(type default)
			)
			(layer "F.Fab")
		)
		(fp_line
			(start -0.12065 0.2794)
			(end -0.12065 0.3048)
			(stroke
				(width 0.1)
				(type default)
			)
			(layer "F.Fab")
		)
		(fp_line
			(start -0.12065 -0.2794)
			(end 0.12065 -0.2794)
			(stroke
				(width 0.1)
				(type default)
			)
			(layer "F.Fab")
		)
		(fp_line
			(start -0.12065 -0.305054)
			(end -0.12065 -0.2794)
			(stroke
				(width 0.1)
				(type default)
			)
			(layer "F.Fab")
		)
		(fp_line
			(start -0.67945 0.3048)
			(end -0.67945 -0.305054)
			(stroke
				(width 0.1)
				(type default)
			)
			(layer "F.Fab")
		)
		(fp_line
			(start -0.67945 -0.305054)
			(end -0.12065 -0.305054)
			(stroke
				(width 0.1)
				(type default)
			)
			(layer "F.Fab")
		)
		(pad "1" smd circle
			(at -0.40005 0 180)
			(size 0 0)
			(layers "F.Cu" "F.Mask" "F.Paste")
			(net "IRQ_SML1_PMBUS_ALERT_N")
		)
		(pad "2" smd circle
			(at 0.40005 0 180)
			(size 0 0)
			(layers "F.Cu" "F.Mask" "F.Paste")
			(net "IRQ_PSU_ALERT_R_N")
		)
	)
	(footprint ""
		(layer "F.Cu")
		(at 365.46663 -256.654046 -90)
		(property "Reference" "C988"
			(at 0 0 270)
			(layer "F.SilkS")
			(hide yes)
			(effects
				(font
					(size 1.27 1.27)
				)
			)
		)
		(property "Value" ""
			(at 0 0 270)
			(layer "F.Fab")
			(effects
				(font
					(size 1.27 1.27)
				)
			)
		)
		(duplicate_pad_numbers_are_jumpers no)
		(fp_line
			(start -0.7874 0.4064)
			(end -0.7874 -0.4064)
			(stroke
				(width 0.1524)
				(type default)
			)
			(layer "F.SilkS")
		)
		(fp_line
			(start 0.7874 0.4064)
			(end -0.7874 0.4064)
			(stroke
				(width 0.1524)
				(type default)
			)
			(layer "F.SilkS")
		)
		(fp_line
			(start -0.7874 -0.4064)
			(end 0.7874 -0.4064)
			(stroke
				(width 0.1524)
				(type default)
			)
			(layer "F.SilkS")
		)
		(fp_line
			(start 0.7874 -0.4064)
			(end 0.7874 0.4064)
			(stroke
				(width 0.1524)
				(type default)
			)
			(layer "F.SilkS")
		)
		(fp_line
			(start -0.67945 0.3048)
			(end -0.67945 -0.305054)
			(stroke
				(width 0.1)
				(type default)
			)
			(layer "F.Fab")
		)
		(fp_line
			(start -0.12065 0.3048)
			(end -0.67945 0.3048)
			(stroke
				(width 0.1)
				(type default)
			)
			(layer "F.Fab")
		)
		(fp_line
			(start 0.120396 0.3048)
			(end 0.120396 0.2794)
			(stroke
				(width 0.1)
				(type default)
			)
			(layer "F.Fab")
		)
		(fp_line
			(start 0.67945 0.3048)
			(end 0.120396 0.3048)
			(stroke
				(width 0.1)
				(type default)
			)
			(layer "F.Fab")
		)
		(fp_line
			(start -0.12065 0.2794)
			(end -0.12065 0.3048)
			(stroke
				(width 0.1)
				(type default)
			)
			(layer "F.Fab")
		)
		(fp_line
			(start 0.120396 0.2794)
			(end -0.12065 0.2794)
			(stroke
				(width 0.1)
				(type default)
			)
			(layer "F.Fab")
		)
		(fp_line
			(start -0.12065 -0.2794)
			(end 0.12065 -0.2794)
			(stroke
				(width 0.1)
				(type default)
			)
			(layer "F.Fab")
		)
		(fp_line
			(start 0.12065 -0.2794)
			(end 0.12065 -0.3048)
			(stroke
				(width 0.1)
				(type default)
			)
			(layer "F.Fab")
		)
		(fp_line
			(start 0.12065 -0.3048)
			(end 0.67945 -0.3048)
			(stroke
				(width 0.1)
				(type default)
			)
			(layer "F.Fab")
		)
		(fp_line
			(start 0.67945 -0.3048)
			(end 0.67945 0.3048)
			(stroke
				(width 0.1)
				(type default)
			)
			(layer "F.Fab")
		)
		(fp_line
			(start -0.67945 -0.305054)
			(end -0.12065 -0.305054)
			(stroke
				(width 0.1)
				(type default)
			)
			(layer "F.Fab")
		)
		(fp_line
			(start -0.12065 -0.305054)
			(end -0.12065 -0.2794)
			(stroke
				(width 0.1)
				(type default)
			)
			(layer "F.Fab")
		)
		(pad "1" smd circle
			(at -0.40005 0 270)
			(size 0 0)
			(layers "F.Cu" "F.Mask" "F.Paste")
			(net "PVCCIN_CPU0")
		)
		(pad "2" smd circle
			(at 0.40005 0 270)
			(size 0 0)
			(layers "F.Cu" "F.Mask" "F.Paste")
			(net "GND")
		)
	)
)
